# T6G (Grand Teton) — schematic netlist excerpt (pin names and nets, part order shuffled) for the footprints in the layout excerpt that follows; sources: Cadence DE-HDL packaged netlist, KiCad conversion of 04192023_DAF0TMB3IC0_F0TG_MB_C_brd_V02_OCP.brd

R6855  Q_RES  33 5% CHIP  pkg 0402LF  page 81 : A = P0V9_RETIMER_CPU1_EN_R2 ; B = P0V9_RETIMER_CPU1_EN

X1  TP_TDR_4P_FTS  TP_TDR_4P_DIP EMPTY  pkg TH  page 260
  S1  = TDR_DIFF_80_TOP_DP
  P1  = T1_GND
  P2  = T1_GND
  S2  = TDR_DIFF_80_TOP_DN

(kicad_pcb
	(version 20260206)
	(generator "pcbnew")
	(generator_version "10.0")
	(general
		(thickness 1.6)
		(legacy_teardrops no)
	)
	(paper "A4")
	(title_block
		(title "04192023_DAF0TMB3IC0_F0TG_MB_C_brd_V02_OCP.brd")
		(comment 1 "Grand Teton / footprints 4273-4274 of 8354")
	)
	(layers
		(0 "F.Cu" signal "TOP")
		(4 "In1.Cu" signal "GND")
		(6 "In2.Cu" signal "IN1")
		(8 "In3.Cu" signal "GND1")
		(10 "In4.Cu" signal "IN2")
		(12 "In5.Cu" signal "GND2")
		(14 "In6.Cu" signal "IN3")
		(16 "In7.Cu" signal "GND3")
		(18 "In8.Cu" signal "VCC")
		(20 "In9.Cu" signal "VCC1")
		(22 "In10.Cu" signal "GND4")
		(24 "In11.Cu" signal "IN4")
		(26 "In12.Cu" signal "GND5")
		(28 "In13.Cu" signal "IN5")
		(30 "In14.Cu" signal "GND6")
		(32 "In15.Cu" signal "IN6")
		(34 "In16.Cu" signal "GND7")
		(2 "B.Cu" signal "BOTTOM")
		(9 "F.Adhes" user "F.Adhesive")
		(11 "B.Adhes" user "B.Adhesive")
		(13 "F.Paste" user "Package Geometry/Pastemask Top")
		(15 "B.Paste" user "Package Geometry/Pastemask Bottom")
		(5 "F.SilkS" user "Ref Des/Silkscreen Top")
		(7 "B.SilkS" user "Ref Des/Silkscreen Bottom")
		(1 "F.Mask" user "Board Geometry/Soldermask Top")
		(3 "B.Mask" user "Board Geometry/Soldermask Bottom")
		(17 "Dwgs.User" user "User.Drawings")
		(19 "Cmts.User" user "User.Comments")
		(21 "Eco1.User" user "User.Eco1")
		(23 "Eco2.User" user "User.Eco2")
		(25 "Edge.Cuts" user "Board Geometry/Outline")
		(27 "Margin" user)
		(31 "F.CrtYd" user "Package Geometry/Place Bound Top")
		(29 "B.CrtYd" user "Package Geometry/Place Bound Bottom")
		(35 "F.Fab" user "Ref Des/Assembly Top")
		(33 "B.Fab" user "Ref Des/Assembly Bottom")
	)
	(footprint ""
		(layer "F.Cu")
		(at 525.408906 -298.384214 90)
		(property "Reference" "X1"
			(at -1.830578 2.823718 0)
			(unlocked yes)
			(layer "F.SilkS")
			(effects
				(font
					(size 0.7874 0.5842)
					(thickness 0.1524)
				)
				(justify left)
			)
		)
		(property "Value" ""
			(at 0 0 90)
			(layer "F.Fab")
			(effects
				(font
					(size 1.27 1.27)
				)
			)
		)
		(property "User Part Number" "N_A"
			(at 1.30175 1.27 180)
			(unlocked yes)
			(layer "Cmts.User")
			(hide yes)
			(effects
				(font
					(size 0.635 0.4064)
					(thickness 0.1524)
				)
			)
		)
		(property "Device Type" "TP_TDR_4P_FTS_TH-TP_TDR_4P_DIP,EMPTY,TP15"
			(at 1.30175 1.27 180)
			(unlocked yes)
			(layer "F.Fab")
			(hide yes)
			(effects
				(font
					(size 0.635 0.4064)
					(thickness 0.1524)
				)
			)
		)
		(duplicate_pad_numbers_are_jumpers no)
		(fp_line
			(start 2.54 -1.27)
			(end 0 -1.27)
			(stroke
				(width 0.1524)
				(type default)
			)
			(layer "F.SilkS")
		)
		(fp_line
			(start 0 -1.27)
			(end 0 -0.635)
			(stroke
				(width 0.1524)
				(type default)
			)
			(layer "F.SilkS")
		)
		(fp_line
			(start 2.54 -1.1303)
			(end 2.54 -1.27)
			(stroke
				(width 0.1524)
				(type default)
			)
			(layer "F.SilkS")
		)
		(fp_line
			(start 0 0.635)
			(end 0 1.905)
			(stroke
				(width 0.1524)
				(type default)
			)
			(layer "F.SilkS")
		)
		(fp_line
			(start 2.54 1.4097)
			(end 2.54 1.1303)
			(stroke
				(width 0.1524)
				(type default)
			)
			(layer "F.SilkS")
		)
		(fp_line
			(start 0 3.175)
			(end 0 3.81)
			(stroke
				(width 0.1524)
				(type default)
			)
			(layer "F.SilkS")
		)
		(fp_line
			(start 2.54 3.81)
			(end 2.54 3.6703)
			(stroke
				(width 0.1524)
				(type default)
			)
			(layer "F.SilkS")
		)
		(fp_line
			(start 0 3.81)
			(end 2.54 3.81)
			(stroke
				(width 0.1524)
				(type default)
			)
			(layer "F.SilkS")
		)
		(fp_poly
			(pts
				(xy -0.761746 0) (xy -2.285746 0.762) (xy -2.285746 -0.762)
			)
			(stroke
				(width 0)
				(type default)
			)
			(fill yes)
			(layer "F.SilkS")
		)
		(fp_line
			(start 2.54 -1.27)
			(end 0 -1.27)
			(stroke
				(width 0.1)
				(type default)
			)
			(layer "F.Fab")
		)
		(fp_line
			(start 0 -1.27)
			(end 0 3.81)
			(stroke
				(width 0.1)
				(type default)
			)
			(layer "F.Fab")
		)
		(fp_line
			(start 2.54 3.81)
			(end 2.54 -1.27)
			(stroke
				(width 0.1)
				(type default)
			)
			(layer "F.Fab")
		)
		(fp_line
			(start 0 3.81)
			(end 2.54 3.81)
			(stroke
				(width 0.1)
				(type default)
			)
			(layer "F.Fab")
		)
		(fp_poly
			(pts
				(xy -0.761746 0) (xy -2.285746 -0.762) (xy -2.285746 0.762)
			)
			(stroke
				(width 0)
				(type default)
			)
			(fill yes)
			(layer "F.Fab")
		)
		(pad "1" thru_hole circle
			(at 0 0 90)
			(size 1.0033 1.0033)
			(drill 0.249936)
			(layers "*.Cu" "*.Mask")
			(remove_unused_layers no)
			(net "TDR_DIFF_80_TOP_DP")
			(clearance 0.10795)
			(thermal_gap 0.10795)
			(padstack
				(mode front_inner_back)
				(layer "Inner"
					(shape circle)
					(size 0.8001 0.8001)
					(clearance 0.1524)
				)
				(layer "B.Cu"
					(shape circle)
					(size 1.0033 1.0033)
					(clearance 0.10795)
				)
			)
		)
		(pad "2" thru_hole circle
			(at 2.54 0 90)
			(size 1.9939 1.9939)
			(drill 0.249936)
			(layers "*.Cu" "*.Mask")
			(remove_unused_layers no)
			(net "T1_GND")
			(clearance 0.10795)
			(thermal_gap 0.10795)
			(padstack
				(mode front_inner_back)
				(layer "Inner"
					(shape circle)
					(size 0.8001 0.8001)
					(clearance 0.1524)
				)
				(layer "B.Cu"
					(shape circle)
					(size 1.9939 1.9939)
					(clearance 0.10795)
				)
			)
		)
		(pad "3" thru_hole circle
			(at 2.54 2.54 90)
			(size 1.9939 1.9939)
			(drill 0.249936)
			(layers "*.Cu" "*.Mask")
			(remove_unused_layers no)
			(net "T1_GND")
			(clearance 0.10795)
			(thermal_gap 0.10795)
			(padstack
				(mode front_inner_back)
				(layer "Inner"
					(shape circle)
					(size 0.8001 0.8001)
					(clearance 0.1524)
				)
				(layer "B.Cu"
					(shape circle)
					(size 1.9939 1.9939)
					(clearance 0.10795)
				)
			)
		)
		(pad "4" thru_hole circle
			(at 0 2.54 90)
			(size 1.0033 1.0033)
			(drill 0.249936)
			(layers "*.Cu" "*.Mask")
			(remove_unused_layers no)
			(net "TDR_DIFF_80_TOP_DN")
			(clearance 0.10795)
			(thermal_gap 0.10795)
			(padstack
				(mode front_inner_back)
				(layer "Inner"
					(shape circle)
					(size 0.8001 0.8001)
					(clearance 0.1524)
				)
				(layer "B.Cu"
					(shape circle)
					(size 1.0033 1.0033)
					(clearance 0.10795)
				)
			)
		)
	)
	(footprint ""
		(layer "F.Cu")
		(at 195.2498 -137.668 90)
		(property "Reference" "R6855"
			(at 0 0 90)
			(layer "F.SilkS")
			(hide yes)
			(effects
				(font
					(size 1.27 1.27)
				)
			)
		)
		(property "Value" ""
			(at 0 0 90)
			(layer "F.Fab")
			(effects
				(font
					(size 1.27 1.27)
				)
			)
		)
		(duplicate_pad_numbers_are_jumpers no)
		(fp_line
			(start 0.7874 -0.4064)
			(end 0.7874 0.4064)
			(stroke
				(width 0.1524)
				(type default)
			)
			(layer "F.SilkS")
		)
		(fp_line
			(start -0.7874 -0.4064)
			(end 0.7874 -0.4064)
			(stroke
				(width 0.1524)
				(type default)
			)
			(layer "F.SilkS")
		)
		(fp_line
			(start 0.7874 0.4064)
			(end -0.7874 0.4064)
			(stroke
				(width 0.1524)
				(type default)
			)
			(layer "F.SilkS")
		)
		(fp_line
			(start -0.7874 0.4064)
			(end -0.7874 -0.4064)
			(stroke
				(width 0.1524)
				(type default)
			)
			(layer "F.SilkS")
		)
		(fp_line
			(start -0.12065 -0.305054)
			(end -0.12065 -0.2794)
			(stroke
				(width 0.1)
				(type default)
			)
			(layer "F.Fab")
		)
		(fp_line
			(start -0.67945 -0.305054)
			(end -0.12065 -0.305054)
			(stroke
				(width 0.1)
				(type default)
			)
			(layer "F.Fab")
		)
		(fp_line
			(start 0.67945 -0.3048)
			(end 0.67945 0.3048)
			(stroke
				(width 0.1)
				(type default)
			)
			(layer "F.Fab")
		)
		(fp_line
			(start 0.12065 -0.3048)
			(end 0.67945 -0.3048)
			(stroke
				(width 0.1)
				(type default)
			)
			(layer "F.Fab")
		)
		(fp_line
			(start 0.12065 -0.2794)
			(end 0.12065 -0.3048)
			(stroke
				(width 0.1)
				(type default)
			)
			(layer "F.Fab")
		)
		(fp_line
			(start -0.12065 -0.2794)
			(end 0.12065 -0.2794)
			(stroke
				(width 0.1)
				(type default)
			)
			(layer "F.Fab")
		)
		(fp_line
			(start 0.120396 0.2794)
			(end -0.12065 0.2794)
			(stroke
				(width 0.1)
				(type default)
			)
			(layer "F.Fab")
		)
		(fp_line
			(start -0.12065 0.2794)
			(end -0.12065 0.3048)
			(stroke
				(width 0.1)
				(type default)
			)
			(layer "F.Fab")
		)
		(fp_line
			(start 0.67945 0.3048)
			(end 0.120396 0.3048)
			(stroke
				(width 0.1)
				(type default)
			)
			(layer "F.Fab")
		)
		(fp_line
			(start 0.120396 0.3048)
			(end 0.120396 0.2794)
			(stroke
				(width 0.1)
				(type default)
			)
			(layer "F.Fab")
		)
		(fp_line
			(start -0.12065 0.3048)
			(end -0.67945 0.3048)
			(stroke
				(width 0.1)
				(type default)
			)
			(layer "F.Fab")
		)
		(fp_line
			(start -0.67945 0.3048)
			(end -0.67945 -0.305054)
			(stroke
				(width 0.1)
				(type default)
			)
			(layer "F.Fab")
		)
		(pad "1" smd circle
			(at -0.40005 0 90)
			(size 0 0)
			(layers "F.Cu" "F.Mask" "F.Paste")
			(net "P0V9_RETIMER_CPU1_EN_R2")
		)
		(pad "2" smd circle
			(at 0.40005 0 90)
			(size 0 0)
			(layers "F.Cu" "F.Mask" "F.Paste")
			(net "P0V9_RETIMER_CPU1_EN")
		)
	)
)
